# BASEBOARD_FAB2 (Tioga Pass) — schematic netlist excerpt (pin names and nets, part order shuffled) for the footprints in the layout excerpt that follows; sources: Cadence DE-HDL packaged netlist, KiCad conversion of Wiwynn_Tioga_Pass_MB.brd

R3P42  RES  33.2 1% CHIP  pkg 0402  page 92 : A = FM_CPU1_THERMTRIP_LVT3_R_N ; B = FM_CPU1_THERMTRIP_LVT3_N
R9L2  RES  1.00K 1% CHIP  pkg 0402  page 100 : A = PVDDQ_KLM ; B = M_M_VREF
C1T21  CAP_A  1.0UF 6.3V 10% X6S  pkg 0402V  page 148 : A = PVCCIO_CPU0 ; B = GND

(kicad_pcb
	(version 20260206)
	(generator "pcbnew")
	(generator_version "10.0")
	(general
		(thickness 1.6)
		(legacy_teardrops no)
	)
	(paper "A4")
	(title_block
		(title "Wiwynn_Tioga_Pass_MB.brd")
		(comment 1 "Tioga Pass / footprints 4721-4723 of 4770")
	)
	(layers
		(0 "F.Cu" signal "TOP")
		(4 "In1.Cu" signal "L2GND")
		(6 "In2.Cu" signal "L3")
		(8 "In3.Cu" signal "L4GND")
		(10 "In4.Cu" signal "L5")
		(12 "In5.Cu" signal "L6GND")
		(14 "In6.Cu" signal "L7VCC")
		(16 "In7.Cu" signal "L8VCC")
		(18 "In8.Cu" signal "L9GND")
		(20 "In9.Cu" signal "L10")
		(22 "In10.Cu" signal "L11GND")
		(24 "In11.Cu" signal "L12")
		(26 "In12.Cu" signal "L13GND")
		(2 "B.Cu" signal "BOTTOM")
		(9 "F.Adhes" user "F.Adhesive")
		(11 "B.Adhes" user "B.Adhesive")
		(13 "F.Paste" user "Package Geometry/Pastemask Top")
		(15 "B.Paste" user "Package Geometry/Pastemask Bottom")
		(5 "F.SilkS" user "Ref Des/Silkscreen Top")
		(7 "B.SilkS" user "Ref Des/Silkscreen Bottom")
		(1 "F.Mask" user "Board Geometry/Soldermask Top")
		(3 "B.Mask" user "Board Geometry/Soldermask Bottom")
		(17 "Dwgs.User" user "User.Drawings")
		(19 "Cmts.User" user "User.Comments")
		(21 "Eco1.User" user "User.Eco1")
		(23 "Eco2.User" user "User.Eco2")
		(25 "Edge.Cuts" user "Board Geometry/Outline")
		(27 "Margin" user)
		(31 "F.CrtYd" user "Package Geometry/Place Bound Top")
		(29 "B.CrtYd" user "Package Geometry/Place Bound Bottom")
		(35 "F.Fab" user "Ref Des/Assembly Top")
		(33 "B.Fab" user "Ref Des/Assembly Bottom")
	)
	(footprint ""
		(layer "B.Cu")
		(at 28.674568 -154.559 180)
		(property "Reference" "R9L2"
			(at 0 0 0)
			(layer "B.SilkS")
			(hide yes)
			(effects
				(font
					(size 1.27 1.27)
				)
				(justify mirror)
			)
		)
		(property "Value" ""
			(at 0 0 0)
			(layer "B.Fab")
			(effects
				(font
					(size 1.27 1.27)
				)
				(justify mirror)
			)
		)
		(duplicate_pad_numbers_are_jumpers no)
		(fp_poly
			(pts
				(xy 0.2794 -0.1016) (xy -0.2794 -0.1016) (xy -0.2794 0.9906) (xy 0.2794 0.9906)
			)
			(stroke
				(width 0)
				(type default)
			)
			(fill no)
			(layer "B.CrtYd")
		)
		(fp_line
			(start 0.2794 0.9906)
			(end -0.2794 0.9906)
			(stroke
				(width 0.1)
				(type default)
			)
			(layer "B.Fab")
		)
		(fp_line
			(start 0.2794 -0.1016)
			(end 0.2794 0.9906)
			(stroke
				(width 0.1)
				(type default)
			)
			(layer "B.Fab")
		)
		(fp_line
			(start -0.2794 0.9906)
			(end -0.2794 -0.1016)
			(stroke
				(width 0.1)
				(type default)
			)
			(layer "B.Fab")
		)
		(fp_line
			(start -0.2794 -0.1016)
			(end 0.2794 -0.1016)
			(stroke
				(width 0.1)
				(type default)
			)
			(layer "B.Fab")
		)
		(pad "1" smd rect
			(at 0 0)
			(size 0.508 0.508)
			(layers "B.Cu" "B.Mask" "B.Paste")
			(net "PVDDQ_KLM")
		)
		(pad "2" smd rect
			(at 0 0.889)
			(size 0.508 0.508)
			(layers "B.Cu" "B.Mask" "B.Paste")
			(net "M_M_VREF")
		)
		(zone
			(layer "B.Cu")
			(hatch none 0.5)
			(connect_pads
				(clearance 0)
			)
			(min_thickness 0.25)
			(keepout
				(tracks not_allowed)
				(vias allowed)
				(pads allowed)
				(copperpour not_allowed)
				(footprints allowed)
			)
			(placement
				(enabled no)
				(sheetname "")
			)
			(fill
				(thermal_gap 0.5)
				(thermal_bridge_width 0.5)
				(island_removal_mode 0)
			)
			(polygon
				(pts
					(xy 28.420568 -155.194) (xy 28.928568 -155.194) (xy 28.928568 -154.813) (xy 28.420568 -154.813)
				)
			)
		)
		(zone
			(layer "B.Cu")
			(hatch none 0.5)
			(connect_pads
				(clearance 0)
			)
			(min_thickness 0.25)
			(keepout
				(tracks allowed)
				(vias not_allowed)
				(pads allowed)
				(copperpour not_allowed)
				(footprints allowed)
			)
			(placement
				(enabled no)
				(sheetname "")
			)
			(fill
				(thermal_gap 0.5)
				(thermal_bridge_width 0.5)
				(island_removal_mode 0)
			)
			(polygon
				(pts
					(xy 28.420568 -154.813) (xy 28.928568 -154.813) (xy 28.928568 -155.194) (xy 28.420568 -155.194)
				)
			)
		)
	)
	(footprint ""
		(layer "B.Cu")
		(at 433.833524 -42.91838 90)
		(property "Reference" "C1T21"
			(at 0 0 90)
			(layer "B.SilkS")
			(hide yes)
			(effects
				(font
					(size 1.27 1.27)
				)
				(justify mirror)
			)
		)
		(property "Value" ""
			(at 0 0 90)
			(layer "B.Fab")
			(effects
				(font
					(size 1.27 1.27)
				)
				(justify mirror)
			)
		)
		(duplicate_pad_numbers_are_jumpers no)
		(fp_poly
			(pts
				(xy -0.3048 -0.1016) (xy -0.3048 0.9906) (xy 0.3048 0.9906) (xy 0.3048 -0.1016)
			)
			(stroke
				(width 0)
				(type default)
			)
			(fill no)
			(layer "B.CrtYd")
		)
		(fp_line
			(start 0.3048 -0.1016)
			(end 0.3048 0.9906)
			(stroke
				(width 0.1)
				(type default)
			)
			(layer "B.Fab")
		)
		(fp_line
			(start -0.3048 -0.1016)
			(end 0.3048 -0.1016)
			(stroke
				(width 0.1)
				(type default)
			)
			(layer "B.Fab")
		)
		(fp_line
			(start 0.3048 0.9906)
			(end -0.3048 0.9906)
			(stroke
				(width 0.1)
				(type default)
			)
			(layer "B.Fab")
		)
		(fp_line
			(start -0.3048 0.9906)
			(end -0.3048 -0.1016)
			(stroke
				(width 0.1)
				(type default)
			)
			(layer "B.Fab")
		)
		(pad "1" smd rect
			(at 0 0 270)
			(size 0.508 0.508)
			(layers "B.Cu" "B.Mask" "B.Paste")
			(net "PVCCIO_CPU0")
		)
		(pad "2" smd rect
			(at 0 0.889 270)
			(size 0.508 0.508)
			(layers "B.Cu" "B.Mask" "B.Paste")
			(net "GND")
		)
		(zone
			(layer "B.Cu")
			(hatch none 0.5)
			(connect_pads
				(clearance 0)
			)
			(min_thickness 0.25)
			(keepout
				(tracks allowed)
				(vias not_allowed)
				(pads allowed)
				(copperpour not_allowed)
				(footprints allowed)
			)
			(placement
				(enabled no)
				(sheetname "")
			)
			(fill
				(thermal_gap 0.5)
				(thermal_bridge_width 0.5)
				(island_removal_mode 0)
			)
			(polygon
				(pts
					(xy 434.087524 -43.17238) (xy 434.087524 -42.66438) (xy 434.468524 -42.66438) (xy 434.468524 -43.17238)
				)
			)
		)
		(zone
			(layer "B.Cu")
			(hatch none 0.5)
			(connect_pads
				(clearance 0)
			)
			(min_thickness 0.25)
			(keepout
				(tracks not_allowed)
				(vias allowed)
				(pads allowed)
				(copperpour not_allowed)
				(footprints allowed)
			)
			(placement
				(enabled no)
				(sheetname "")
			)
			(fill
				(thermal_gap 0.5)
				(thermal_bridge_width 0.5)
				(island_removal_mode 0)
			)
			(polygon
				(pts
					(xy 434.468524 -43.17238) (xy 434.468524 -42.66438) (xy 434.087524 -42.66438) (xy 434.087524 -43.17238)
				)
			)
		)
	)
	(footprint ""
		(layer "B.Cu")
		(at 369.443 -62.9285 180)
		(property "Reference" "R3P42"
			(at 0 0 0)
			(layer "B.SilkS")
			(hide yes)
			(effects
				(font
					(size 1.27 1.27)
				)
				(justify mirror)
			)
		)
		(property "Value" ""
			(at 0 0 0)
			(layer "B.Fab")
			(effects
				(font
					(size 1.27 1.27)
				)
				(justify mirror)
			)
		)
		(duplicate_pad_numbers_are_jumpers no)
		(fp_poly
			(pts
				(xy 0.2794 -0.1016) (xy -0.2794 -0.1016) (xy -0.2794 0.9906) (xy 0.2794 0.9906)
			)
			(stroke
				(width 0)
				(type default)
			)
			(fill no)
			(layer "B.CrtYd")
		)
		(fp_line
			(start 0.2794 0.9906)
			(end -0.2794 0.9906)
			(stroke
				(width 0.1)
				(type default)
			)
			(layer "B.Fab")
		)
		(fp_line
			(start 0.2794 -0.1016)
			(end 0.2794 0.9906)
			(stroke
				(width 0.1)
				(type default)
			)
			(layer "B.Fab")
		)
		(fp_line
			(start -0.2794 0.9906)
			(end -0.2794 -0.1016)
			(stroke
				(width 0.1)
				(type default)
			)
			(layer "B.Fab")
		)
		(fp_line
			(start -0.2794 -0.1016)
			(end 0.2794 -0.1016)
			(stroke
				(width 0.1)
				(type default)
			)
			(layer "B.Fab")
		)
		(pad "1" smd rect
			(at 0 0)
			(size 0.508 0.508)
			(layers "B.Cu" "B.Mask" "B.Paste")
			(net "FM_CPU1_THERMTRIP_LVT3_R_N")
		)
		(pad "2" smd rect
			(at 0 0.889)
			(size 0.508 0.508)
			(layers "B.Cu" "B.Mask" "B.Paste")
			(net "FM_CPU1_THERMTRIP_LVT3_N")
		)
		(zone
			(layer "B.Cu")
			(hatch none 0.5)
			(connect_pads
				(clearance 0)
			)
			(min_thickness 0.25)
			(keepout
				(tracks not_allowed)
				(vias allowed)
				(pads allowed)
				(copperpour not_allowed)
				(footprints allowed)
			)
			(placement
				(enabled no)
				(sheetname "")
			)
			(fill
				(thermal_gap 0.5)
				(thermal_bridge_width 0.5)
				(island_removal_mode 0)
			)
			(polygon
				(pts
					(xy 369.189 -63.5635) (xy 369.697 -63.5635) (xy 369.697 -63.1825) (xy 369.189 -63.1825)
				)
			)
		)
		(zone
			(layer "B.Cu")
			(hatch none 0.5)
			(connect_pads
				(clearance 0)
			)
			(min_thickness 0.25)
			(keepout
				(tracks allowed)
				(vias not_allowed)
				(pads allowed)
				(copperpour not_allowed)
				(footprints allowed)
			)
			(placement
				(enabled no)
				(sheetname "")
			)
			(fill
				(thermal_gap 0.5)
				(thermal_bridge_width 0.5)
				(island_removal_mode 0)
			)
			(polygon
				(pts
					(xy 369.189 -63.1825) (xy 369.697 -63.1825) (xy 369.697 -63.5635) (xy 369.189 -63.5635)
				)
			)
		)
	)
)
